(kicad_pcb
	(version 20260206)
	(generator "pcbnew")
	(generator_version "10.0")
	(general
		(thickness 1.6)
		(legacy_teardrops no)
	)
	(paper "A4")
	(title_block
		(title "03242023_DA0F0TMBIJ0_F0T_Motherboard_J_brd_V01_OCP.brd")
		(comment 1 "Grand Teton / footprints 4884-4890 of 6105")
	)
	(layers
		(0 "F.Cu" signal "TOP")
		(4 "In1.Cu" signal "GND")
		(6 "In2.Cu" signal "IN1")
		(8 "In3.Cu" signal "GND1")
		(10 "In4.Cu" signal "IN2")
		(12 "In5.Cu" signal "GND2")
		(14 "In6.Cu" signal "IN3")
		(16 "In7.Cu" signal "GND3")
		(18 "In8.Cu" signal "VCC")
		(20 "In9.Cu" signal "VCC1")
		(22 "In10.Cu" signal "GND4")
		(24 "In11.Cu" signal "IN4")
		(26 "In12.Cu" signal "GND5")
		(28 "In13.Cu" signal "IN5")
		(30 "In14.Cu" signal "GND6")
		(32 "In15.Cu" signal "IN6")
		(34 "In16.Cu" signal "GND7")
		(2 "B.Cu" signal "BOTTOM")
		(9 "F.Adhes" user "F.Adhesive")
		(11 "B.Adhes" user "B.Adhesive")
		(13 "F.Paste" user "Package Geometry/Pastemask Top")
		(15 "B.Paste" user "Package Geometry/Pastemask Bottom")
		(5 "F.SilkS" user "Ref Des/Silkscreen Top")
		(7 "B.SilkS" user "Ref Des/Silkscreen Bottom")
		(1 "F.Mask" user "Board Geometry/Soldermask Top")
		(3 "B.Mask" user "Board Geometry/Soldermask Bottom")
		(17 "Dwgs.User" user "User.Drawings")
		(19 "Cmts.User" user "User.Comments")
		(21 "Eco1.User" user "User.Eco1")
		(23 "Eco2.User" user "User.Eco2")
		(25 "Edge.Cuts" user "Board Geometry/Outline")
		(27 "Margin" user)
		(31 "F.CrtYd" user "Package Geometry/Place Bound Top")
		(29 "B.CrtYd" user "Package Geometry/Place Bound Bottom")
		(35 "F.Fab" user "Ref Des/Assembly Top")
		(33 "B.Fab" user "Ref Des/Assembly Bottom")
	)
	(footprint ""
		(layer "B.Cu")
		(at 66.149982 -15.32763)
		(property "Reference" "C1834"
			(at 0 0 0)
			(layer "B.SilkS")
			(hide yes)
			(effects
				(font
					(size 1.27 1.27)
				)
				(justify mirror)
			)
		)
		(property "Value" ""
			(at 0 0 0)
			(layer "B.Fab")
			(effects
				(font
					(size 1.27 1.27)
				)
				(justify mirror)
			)
		)
		(duplicate_pad_numbers_are_jumpers no)
		(fp_line
			(start -0.7874 -0.4064)
			(end -0.7874 0.4064)
			(stroke
				(width 0.1524)
				(type default)
			)
			(layer "B.SilkS")
		)
		(fp_line
			(start -0.7874 0.4064)
			(end 0.7874 0.4064)
			(stroke
				(width 0.1524)
				(type default)
			)
			(layer "B.SilkS")
		)
		(fp_line
			(start 0.7874 -0.4064)
			(end -0.7874 -0.4064)
			(stroke
				(width 0.1524)
				(type default)
			)
			(layer "B.SilkS")
		)
		(fp_line
			(start 0.7874 0.4064)
			(end 0.7874 -0.4064)
			(stroke
				(width 0.1524)
				(type default)
			)
			(layer "B.SilkS")
		)
		(fp_line
			(start -0.67945 -0.3048)
			(end -0.67945 0.3048)
			(stroke
				(width 0.1)
				(type default)
			)
			(layer "B.Fab")
		)
		(fp_line
			(start -0.67945 0.3048)
			(end -0.120396 0.3048)
			(stroke
				(width 0.1)
				(type default)
			)
			(layer "B.Fab")
		)
		(fp_line
			(start -0.12065 -0.3048)
			(end -0.67945 -0.3048)
			(stroke
				(width 0.1)
				(type default)
			)
			(layer "B.Fab")
		)
		(fp_line
			(start -0.12065 -0.2794)
			(end -0.12065 -0.3048)
			(stroke
				(width 0.1)
				(type default)
			)
			(layer "B.Fab")
		)
		(fp_line
			(start -0.120396 0.2794)
			(end 0.12065 0.2794)
			(stroke
				(width 0.1)
				(type default)
			)
			(layer "B.Fab")
		)
		(fp_line
			(start -0.120396 0.3048)
			(end -0.120396 0.2794)
			(stroke
				(width 0.1)
				(type default)
			)
			(layer "B.Fab")
		)
		(fp_line
			(start 0.12065 -0.305054)
			(end 0.12065 -0.2794)
			(stroke
				(width 0.1)
				(type default)
			)
			(layer "B.Fab")
		)
		(fp_line
			(start 0.12065 -0.2794)
			(end -0.12065 -0.2794)
			(stroke
				(width 0.1)
				(type default)
			)
			(layer "B.Fab")
		)
		(fp_line
			(start 0.12065 0.2794)
			(end 0.12065 0.3048)
			(stroke
				(width 0.1)
				(type default)
			)
			(layer "B.Fab")
		)
		(fp_line
			(start 0.12065 0.3048)
			(end 0.67945 0.3048)
			(stroke
				(width 0.1)
				(type default)
			)
			(layer "B.Fab")
		)
		(fp_line
			(start 0.67945 -0.305054)
			(end 0.12065 -0.305054)
			(stroke
				(width 0.1)
				(type default)
			)
			(layer "B.Fab")
		)
		(fp_line
			(start 0.67945 0.3048)
			(end 0.67945 -0.305054)
			(stroke
				(width 0.1)
				(type default)
			)
			(layer "B.Fab")
		)
		(pad "1" smd circle
			(at 0.40005 0 180)
			(size 0 0)
			(layers "B.Cu" "B.Mask" "B.Paste")
			(net "P12V_OCP_V3_2")
		)
		(pad "2" smd circle
			(at -0.40005 0 180)
			(size 0 0)
			(layers "B.Cu" "B.Mask" "B.Paste")
			(net "GND")
		)
	)
	(footprint ""
		(layer "B.Cu")
		(at 174.814738 -97.32137 -90)
		(property "Reference" "R1326"
			(at 0 0 90)
			(layer "B.SilkS")
			(hide yes)
			(effects
				(font
					(size 1.27 1.27)
				)
				(justify mirror)
			)
		)
		(property "Value" ""
			(at 0 0 90)
			(layer "B.Fab")
			(effects
				(font
					(size 1.27 1.27)
				)
				(justify mirror)
			)
		)
		(duplicate_pad_numbers_are_jumpers no)
		(fp_line
			(start -0.7874 0.4064)
			(end 0.7874 0.4064)
			(stroke
				(width 0.1524)
				(type default)
			)
			(layer "B.SilkS")
		)
		(fp_line
			(start 0.7874 0.4064)
			(end 0.7874 -0.4064)
			(stroke
				(width 0.1524)
				(type default)
			)
			(layer "B.SilkS")
		)
		(fp_line
			(start -0.7874 -0.4064)
			(end -0.7874 0.4064)
			(stroke
				(width 0.1524)
				(type default)
			)
			(layer "B.SilkS")
		)
		(fp_line
			(start 0.7874 -0.4064)
			(end -0.7874 -0.4064)
			(stroke
				(width 0.1524)
				(type default)
			)
			(layer "B.SilkS")
		)
		(fp_line
			(start -0.67945 0.3048)
			(end -0.120396 0.3048)
			(stroke
				(width 0.1)
				(type default)
			)
			(layer "B.Fab")
		)
		(fp_line
			(start -0.120396 0.3048)
			(end -0.120396 0.2794)
			(stroke
				(width 0.1)
				(type default)
			)
			(layer "B.Fab")
		)
		(fp_line
			(start 0.12065 0.3048)
			(end 0.67945 0.3048)
			(stroke
				(width 0.1)
				(type default)
			)
			(layer "B.Fab")
		)
		(fp_line
			(start 0.67945 0.3048)
			(end 0.67945 -0.305054)
			(stroke
				(width 0.1)
				(type default)
			)
			(layer "B.Fab")
		)
		(fp_line
			(start -0.120396 0.2794)
			(end 0.12065 0.2794)
			(stroke
				(width 0.1)
				(type default)
			)
			(layer "B.Fab")
		)
		(fp_line
			(start 0.12065 0.2794)
			(end 0.12065 0.3048)
			(stroke
				(width 0.1)
				(type default)
			)
			(layer "B.Fab")
		)
		(fp_line
			(start -0.12065 -0.2794)
			(end -0.12065 -0.3048)
			(stroke
				(width 0.1)
				(type default)
			)
			(layer "B.Fab")
		)
		(fp_line
			(start 0.12065 -0.2794)
			(end -0.12065 -0.2794)
			(stroke
				(width 0.1)
				(type default)
			)
			(layer "B.Fab")
		)
		(fp_line
			(start -0.67945 -0.3048)
			(end -0.67945 0.3048)
			(stroke
				(width 0.1)
				(type default)
			)
			(layer "B.Fab")
		)
		(fp_line
			(start -0.12065 -0.3048)
			(end -0.67945 -0.3048)
			(stroke
				(width 0.1)
				(type default)
			)
			(layer "B.Fab")
		)
		(fp_line
			(start 0.12065 -0.305054)
			(end 0.12065 -0.2794)
			(stroke
				(width 0.1)
				(type default)
			)
			(layer "B.Fab")
		)
		(fp_line
			(start 0.67945 -0.305054)
			(end 0.12065 -0.305054)
			(stroke
				(width 0.1)
				(type default)
			)
			(layer "B.Fab")
		)
		(pad "1" smd circle
			(at 0.40005 0 90)
			(size 0 0)
			(layers "B.Cu" "B.Mask" "B.Paste")
			(net "PWRGD_DRAMPWRGD_CPU0_CD_R_LVC1")
		)
		(pad "2" smd circle
			(at -0.40005 0 90)
			(size 0 0)
			(layers "B.Cu" "B.Mask" "B.Paste")
			(net "GND")
		)
	)
	(footprint ""
		(layer "B.Cu")
		(at 327.522586 -333.628492 -90)
		(property "Reference" "PC247_P0_7"
			(at 0 0 90)
			(layer "B.SilkS")
			(hide yes)
			(effects
				(font
					(size 1.27 1.27)
				)
				(justify mirror)
			)
		)
		(property "Value" ""
			(at 0 0 90)
			(layer "B.Fab")
			(effects
				(font
					(size 1.27 1.27)
				)
				(justify mirror)
			)
		)
		(duplicate_pad_numbers_are_jumpers no)
		(fp_line
			(start -1.524 0.762)
			(end 1.524 0.762)
			(stroke
				(width 0.1524)
				(type default)
			)
			(layer "B.SilkS")
		)
		(fp_line
			(start 1.524 0.762)
			(end 1.524 -0.762)
			(stroke
				(width 0.1524)
				(type default)
			)
			(layer "B.SilkS")
		)
		(fp_line
			(start -1.524 -0.762)
			(end -1.524 0.762)
			(stroke
				(width 0.1524)
				(type default)
			)
			(layer "B.SilkS")
		)
		(fp_line
			(start 1.524 -0.762)
			(end -1.524 -0.762)
			(stroke
				(width 0.1524)
				(type default)
			)
			(layer "B.SilkS")
		)
		(fp_line
			(start -1.1049 0.724916)
			(end -1.1049 -0.724916)
			(stroke
				(width 0.1)
				(type default)
			)
			(layer "B.Fab")
		)
		(fp_line
			(start 1.1049 0.724916)
			(end -1.1049 0.724916)
			(stroke
				(width 0.1)
				(type default)
			)
			(layer "B.Fab")
		)
		(fp_line
			(start -1.1049 -0.724916)
			(end 1.1049 -0.724916)
			(stroke
				(width 0.1)
				(type default)
			)
			(layer "B.Fab")
		)
		(fp_line
			(start 1.1049 -0.724916)
			(end 1.1049 0.724916)
			(stroke
				(width 0.1)
				(type default)
			)
			(layer "B.Fab")
		)
		(pad "1" smd rect
			(at 0.889 0 270)
			(size 1.016 1.27)
			(layers "B.Cu" "B.Mask" "B.Paste")
			(net "PVCCIN_CPU0")
		)
		(pad "2" smd rect
			(at -0.889 0 270)
			(size 1.016 1.27)
			(layers "B.Cu" "B.Mask" "B.Paste")
			(net "GND")
		)
	)
	(footprint ""
		(layer "B.Cu")
		(at 409.30957 -156.642054 180)
		(property "Reference" "PC184"
			(at 0 0 0)
			(layer "B.SilkS")
			(hide yes)
			(effects
				(font
					(size 1.27 1.27)
				)
				(justify mirror)
			)
		)
		(property "Value" ""
			(at 0 0 0)
			(layer "B.Fab")
			(effects
				(font
					(size 1.27 1.27)
				)
				(justify mirror)
			)
		)
		(duplicate_pad_numbers_are_jumpers no)
		(fp_line
			(start 1.524 0.762)
			(end 1.524 -0.762)
			(stroke
				(width 0.1524)
				(type default)
			)
			(layer "B.SilkS")
		)
		(fp_line
			(start 1.524 -0.762)
			(end -1.524 -0.762)
			(stroke
				(width 0.1524)
				(type default)
			)
			(layer "B.SilkS")
		)
		(fp_line
			(start -1.524 0.762)
			(end 1.524 0.762)
			(stroke
				(width 0.1524)
				(type default)
			)
			(layer "B.SilkS")
		)
		(fp_line
			(start -1.524 -0.762)
			(end -1.524 0.762)
			(stroke
				(width 0.1524)
				(type default)
			)
			(layer "B.SilkS")
		)
		(fp_line
			(start 1.1049 0.724916)
			(end -1.1049 0.724916)
			(stroke
				(width 0.1)
				(type default)
			)
			(layer "B.Fab")
		)
		(fp_line
			(start 1.1049 -0.724916)
			(end 1.1049 0.724916)
			(stroke
				(width 0.1)
				(type default)
			)
			(layer "B.Fab")
		)
		(fp_line
			(start -1.1049 0.724916)
			(end -1.1049 -0.724916)
			(stroke
				(width 0.1)
				(type default)
			)
			(layer "B.Fab")
		)
		(fp_line
			(start -1.1049 -0.724916)
			(end 1.1049 -0.724916)
			(stroke
				(width 0.1)
				(type default)
			)
			(layer "B.Fab")
		)
		(pad "1" smd rect
			(at 0.889 0 180)
			(size 1.016 1.27)
			(layers "B.Cu" "B.Mask" "B.Paste")
			(net "PVCCFA_EHV_CPU0")
		)
		(pad "2" smd rect
			(at -0.889 0 180)
			(size 1.016 1.27)
			(layers "B.Cu" "B.Mask" "B.Paste")
			(net "GND")
		)
	)
	(footprint ""
		(layer "B.Cu")
		(at 177.123344 -192.699894 -90)
		(property "Reference" "R266"
			(at 0 0 90)
			(layer "B.SilkS")
			(hide yes)
			(effects
				(font
					(size 1.27 1.27)
				)
				(justify mirror)
			)
		)
		(property "Value" ""
			(at 0 0 90)
			(layer "B.Fab")
			(effects
				(font
					(size 1.27 1.27)
				)
				(justify mirror)
			)
		)
		(duplicate_pad_numbers_are_jumpers no)
		(fp_line
			(start -0.7874 0.4064)
			(end 0.7874 0.4064)
			(stroke
				(width 0.1524)
				(type default)
			)
			(layer "B.SilkS")
		)
		(fp_line
			(start 0.7874 0.4064)
			(end 0.7874 -0.4064)
			(stroke
				(width 0.1524)
				(type default)
			)
			(layer "B.SilkS")
		)
		(fp_line
			(start -0.7874 -0.4064)
			(end -0.7874 0.4064)
			(stroke
				(width 0.1524)
				(type default)
			)
			(layer "B.SilkS")
		)
		(fp_line
			(start 0.7874 -0.4064)
			(end -0.7874 -0.4064)
			(stroke
				(width 0.1524)
				(type default)
			)
			(layer "B.SilkS")
		)
		(fp_line
			(start -0.67945 0.3048)
			(end -0.120396 0.3048)
			(stroke
				(width 0.1)
				(type default)
			)
			(layer "B.Fab")
		)
		(fp_line
			(start -0.120396 0.3048)
			(end -0.120396 0.2794)
			(stroke
				(width 0.1)
				(type default)
			)
			(layer "B.Fab")
		)
		(fp_line
			(start 0.12065 0.3048)
			(end 0.67945 0.3048)
			(stroke
				(width 0.1)
				(type default)
			)
			(layer "B.Fab")
		)
		(fp_line
			(start 0.67945 0.3048)
			(end 0.67945 -0.305054)
			(stroke
				(width 0.1)
				(type default)
			)
			(layer "B.Fab")
		)
		(fp_line
			(start -0.120396 0.2794)
			(end 0.12065 0.2794)
			(stroke
				(width 0.1)
				(type default)
			)
			(layer "B.Fab")
		)
		(fp_line
			(start 0.12065 0.2794)
			(end 0.12065 0.3048)
			(stroke
				(width 0.1)
				(type default)
			)
			(layer "B.Fab")
		)
		(fp_line
			(start -0.12065 -0.2794)
			(end -0.12065 -0.3048)
			(stroke
				(width 0.1)
				(type default)
			)
			(layer "B.Fab")
		)
		(fp_line
			(start 0.12065 -0.2794)
			(end -0.12065 -0.2794)
			(stroke
				(width 0.1)
				(type default)
			)
			(layer "B.Fab")
		)
		(fp_line
			(start -0.67945 -0.3048)
			(end -0.67945 0.3048)
			(stroke
				(width 0.1)
				(type default)
			)
			(layer "B.Fab")
		)
		(fp_line
			(start -0.12065 -0.3048)
			(end -0.67945 -0.3048)
			(stroke
				(width 0.1)
				(type default)
			)
			(layer "B.Fab")
		)
		(fp_line
			(start 0.12065 -0.305054)
			(end 0.12065 -0.2794)
			(stroke
				(width 0.1)
				(type default)
			)
			(layer "B.Fab")
		)
		(fp_line
			(start 0.67945 -0.305054)
			(end 0.12065 -0.305054)
			(stroke
				(width 0.1)
				(type default)
			)
			(layer "B.Fab")
		)
		(pad "1" smd circle
			(at 0.40005 0 90)
			(size 0 0)
			(layers "B.Cu" "B.Mask" "B.Paste")
			(net "PVNN_TERM_CPU1")
		)
		(pad "2" smd circle
			(at -0.40005 0 90)
			(size 0 0)
			(layers "B.Cu" "B.Mask" "B.Paste")
			(net "PU_CPU1_SOCKET_ID1")
		)
	)
	(footprint ""
		(layer "B.Cu")
		(at 299.596048 -362.795058 90)
		(property "Reference" "PC609_P0_2"
			(at 0 0 90)
			(layer "B.SilkS")
			(hide yes)
			(effects
				(font
					(size 1.27 1.27)
				)
				(justify mirror)
			)
		)
		(property "Value" ""
			(at 0 0 90)
			(layer "B.Fab")
			(effects
				(font
					(size 1.27 1.27)
				)
				(justify mirror)
			)
		)
		(duplicate_pad_numbers_are_jumpers no)
		(fp_line
			(start 1.524 -0.762)
			(end -1.524 -0.762)
			(stroke
				(width 0.1524)
				(type default)
			)
			(layer "B.SilkS")
		)
		(fp_line
			(start -1.524 -0.762)
			(end -1.524 0.762)
			(stroke
				(width 0.1524)
				(type default)
			)
			(layer "B.SilkS")
		)
		(fp_line
			(start 1.524 0.762)
			(end 1.524 -0.762)
			(stroke
				(width 0.1524)
				(type default)
			)
			(layer "B.SilkS")
		)
		(fp_line
			(start -1.524 0.762)
			(end 1.524 0.762)
			(stroke
				(width 0.1524)
				(type default)
			)
			(layer "B.SilkS")
		)
		(fp_line
			(start 1.1049 -0.724916)
			(end 1.1049 0.724916)
			(stroke
				(width 0.1)
				(type default)
			)
			(layer "B.Fab")
		)
		(fp_line
			(start -1.1049 -0.724916)
			(end 1.1049 -0.724916)
			(stroke
				(width 0.1)
				(type default)
			)
			(layer "B.Fab")
		)
		(fp_line
			(start 1.1049 0.724916)
			(end -1.1049 0.724916)
			(stroke
				(width 0.1)
				(type default)
			)
			(layer "B.Fab")
		)
		(fp_line
			(start -1.1049 0.724916)
			(end -1.1049 -0.724916)
			(stroke
				(width 0.1)
				(type default)
			)
			(layer "B.Fab")
		)
		(pad "1" smd rect
			(at 0.889 0 90)
			(size 1.016 1.27)
			(layers "B.Cu" "B.Mask" "B.Paste")
			(net "SW_P12V_PVCCFA_EHV_FIVRA_CPU0_L")
		)
		(pad "2" smd rect
			(at -0.889 0 90)
			(size 1.016 1.27)
			(layers "B.Cu" "B.Mask" "B.Paste")
			(net "GND")
		)
	)
	(footprint ""
		(layer "B.Cu")
		(at 27.0383 -131.55295 180)
		(property "Reference" "PR258"
			(at 0 0 0)
			(layer "B.SilkS")
			(hide yes)
			(effects
				(font
					(size 1.27 1.27)
				)
				(justify mirror)
			)
		)
		(property "Value" ""
			(at 0 0 0)
			(layer "B.Fab")
			(effects
				(font
					(size 1.27 1.27)
				)
				(justify mirror)
			)
		)
		(duplicate_pad_numbers_are_jumpers no)
		(fp_line
			(start 0.7874 0.4064)
			(end 0.7874 -0.4064)
			(stroke
				(width 0.1524)
				(type default)
			)
			(layer "B.SilkS")
		)
		(fp_line
			(start 0.7874 -0.4064)
			(end -0.7874 -0.4064)
			(stroke
				(width 0.1524)
				(type default)
			)
			(layer "B.SilkS")
		)
		(fp_line
			(start -0.7874 0.4064)
			(end 0.7874 0.4064)
			(stroke
				(width 0.1524)
				(type default)
			)
			(layer "B.SilkS")
		)
		(fp_line
			(start -0.7874 -0.4064)
			(end -0.7874 0.4064)
			(stroke
				(width 0.1524)
				(type default)
			)
			(layer "B.SilkS")
		)
		(fp_line
			(start 0.67945 0.3048)
			(end 0.67945 -0.305054)
			(stroke
				(width 0.1)
				(type default)
			)
			(layer "B.Fab")
		)
		(fp_line
			(start 0.67945 -0.305054)
			(end 0.12065 -0.305054)
			(stroke
				(width 0.1)
				(type default)
			)
			(layer "B.Fab")
		)
		(fp_line
			(start 0.12065 0.3048)
			(end 0.67945 0.3048)
			(stroke
				(width 0.1)
				(type default)
			)
			(layer "B.Fab")
		)
		(fp_line
			(start 0.12065 0.2794)
			(end 0.12065 0.3048)
			(stroke
				(width 0.1)
				(type default)
			)
			(layer "B.Fab")
		)
		(fp_line
			(start 0.12065 -0.2794)
			(end -0.12065 -0.2794)
			(stroke
				(width 0.1)
				(type default)
			)
			(layer "B.Fab")
		)
		(fp_line
			(start 0.12065 -0.305054)
			(end 0.12065 -0.2794)
			(stroke
				(width 0.1)
				(type default)
			)
			(layer "B.Fab")
		)
		(fp_line
			(start -0.120396 0.3048)
			(end -0.120396 0.2794)
			(stroke
				(width 0.1)
				(type default)
			)
			(layer "B.Fab")
		)
		(fp_line
			(start -0.120396 0.2794)
			(end 0.12065 0.2794)
			(stroke
				(width 0.1)
				(type default)
			)
			(layer "B.Fab")
		)
		(fp_line
			(start -0.12065 -0.2794)
			(end -0.12065 -0.3048)
			(stroke
				(width 0.1)
				(type default)
			)
			(layer "B.Fab")
		)
		(fp_line
			(start -0.12065 -0.3048)
			(end -0.67945 -0.3048)
			(stroke
				(width 0.1)
				(type default)
			)
			(layer "B.Fab")
		)
		(fp_line
			(start -0.67945 0.3048)
			(end -0.120396 0.3048)
			(stroke
				(width 0.1)
				(type default)
			)
			(layer "B.Fab")
		)
		(fp_line
			(start -0.67945 -0.3048)
			(end -0.67945 0.3048)
			(stroke
				(width 0.1)
				(type default)
			)
			(layer "B.Fab")
		)
		(pad "1" smd circle
			(at 0.40005 0)
			(size 0 0)
			(layers "B.Cu" "B.Mask" "B.Paste")
			(net "PVCCINFAON_CPU1_VREF")
		)
		(pad "2" smd circle
			(at -0.40005 0)
			(size 0 0)
			(layers "B.Cu" "B.Mask" "B.Paste")
			(net "PVCCINFAON_CPU1_ADDR")
		)
	)
)
